# T6G (Grand Teton) — schematic netlist excerpt (pin names and nets, part order shuffled) for the footprints in the layout excerpt that follows; sources: Cadence DE-HDL packaged netlist, KiCad conversion of 04192023_DAF0TMB3IC0_F0TG_MB_C_brd_V02_OCP.brd

R4157  Q_RES  33.2 1% CHIP  pkg 0402LF  page 81 : A = PRSNT_CABLE_GPU_A1_ISO_R_N ; B = PRSNT_CABLE_GPU_A1_ISO_N
R2530  Q_RES  4.7K 5% CHIP  pkg 0402LF  page 242 : A = P12V_AUX ; B = P12V_AUX_BLEEDING

(kicad_pcb
	(version 20260206)
	(generator "pcbnew")
	(generator_version "10.0")
	(general
		(thickness 1.6)
		(legacy_teardrops no)
	)
	(paper "A4")
	(title_block
		(title "04192023_DAF0TMB3IC0_F0TG_MB_C_brd_V02_OCP.brd")
		(comment 1 "Grand Teton / footprints 4178-4179 of 8354")
	)
	(layers
		(0 "F.Cu" signal "TOP")
		(4 "In1.Cu" signal "GND")
		(6 "In2.Cu" signal "IN1")
		(8 "In3.Cu" signal "GND1")
		(10 "In4.Cu" signal "IN2")
		(12 "In5.Cu" signal "GND2")
		(14 "In6.Cu" signal "IN3")
		(16 "In7.Cu" signal "GND3")
		(18 "In8.Cu" signal "VCC")
		(20 "In9.Cu" signal "VCC1")
		(22 "In10.Cu" signal "GND4")
		(24 "In11.Cu" signal "IN4")
		(26 "In12.Cu" signal "GND5")
		(28 "In13.Cu" signal "IN5")
		(30 "In14.Cu" signal "GND6")
		(32 "In15.Cu" signal "IN6")
		(34 "In16.Cu" signal "GND7")
		(2 "B.Cu" signal "BOTTOM")
		(9 "F.Adhes" user "F.Adhesive")
		(11 "B.Adhes" user "B.Adhesive")
		(13 "F.Paste" user "Package Geometry/Pastemask Top")
		(15 "B.Paste" user "Package Geometry/Pastemask Bottom")
		(5 "F.SilkS" user "Ref Des/Silkscreen Top")
		(7 "B.SilkS" user "Ref Des/Silkscreen Bottom")
		(1 "F.Mask" user "Board Geometry/Soldermask Top")
		(3 "B.Mask" user "Board Geometry/Soldermask Bottom")
		(17 "Dwgs.User" user "User.Drawings")
		(19 "Cmts.User" user "User.Comments")
		(21 "Eco1.User" user "User.Eco1")
		(23 "Eco2.User" user "User.Eco2")
		(25 "Edge.Cuts" user "Board Geometry/Outline")
		(27 "Margin" user)
		(31 "F.CrtYd" user "Package Geometry/Place Bound Top")
		(29 "B.CrtYd" user "Package Geometry/Place Bound Bottom")
		(35 "F.Fab" user "Ref Des/Assembly Top")
		(33 "B.Fab" user "Ref Des/Assembly Bottom")
	)
	(footprint ""
		(layer "F.Cu")
		(at 212.0265 -144.201388 -90)
		(property "Reference" "R2530"
			(at 0 0 270)
			(layer "F.SilkS")
			(hide yes)
			(effects
				(font
					(size 1.27 1.27)
				)
			)
		)
		(property "Value" ""
			(at 0 0 270)
			(layer "F.Fab")
			(effects
				(font
					(size 1.27 1.27)
				)
			)
		)
		(duplicate_pad_numbers_are_jumpers no)
		(fp_line
			(start -0.7874 0.4064)
			(end -0.7874 -0.4064)
			(stroke
				(width 0.1524)
				(type default)
			)
			(layer "F.SilkS")
		)
		(fp_line
			(start 0.7874 0.4064)
			(end -0.7874 0.4064)
			(stroke
				(width 0.1524)
				(type default)
			)
			(layer "F.SilkS")
		)
		(fp_line
			(start -0.7874 -0.4064)
			(end 0.7874 -0.4064)
			(stroke
				(width 0.1524)
				(type default)
			)
			(layer "F.SilkS")
		)
		(fp_line
			(start 0.7874 -0.4064)
			(end 0.7874 0.4064)
			(stroke
				(width 0.1524)
				(type default)
			)
			(layer "F.SilkS")
		)
		(fp_line
			(start -0.67945 0.3048)
			(end -0.67945 -0.305054)
			(stroke
				(width 0.1)
				(type default)
			)
			(layer "F.Fab")
		)
		(fp_line
			(start -0.12065 0.3048)
			(end -0.67945 0.3048)
			(stroke
				(width 0.1)
				(type default)
			)
			(layer "F.Fab")
		)
		(fp_line
			(start 0.120396 0.3048)
			(end 0.120396 0.2794)
			(stroke
				(width 0.1)
				(type default)
			)
			(layer "F.Fab")
		)
		(fp_line
			(start 0.67945 0.3048)
			(end 0.120396 0.3048)
			(stroke
				(width 0.1)
				(type default)
			)
			(layer "F.Fab")
		)
		(fp_line
			(start -0.12065 0.2794)
			(end -0.12065 0.3048)
			(stroke
				(width 0.1)
				(type default)
			)
			(layer "F.Fab")
		)
		(fp_line
			(start 0.120396 0.2794)
			(end -0.12065 0.2794)
			(stroke
				(width 0.1)
				(type default)
			)
			(layer "F.Fab")
		)
		(fp_line
			(start -0.12065 -0.2794)
			(end 0.12065 -0.2794)
			(stroke
				(width 0.1)
				(type default)
			)
			(layer "F.Fab")
		)
		(fp_line
			(start 0.12065 -0.2794)
			(end 0.12065 -0.3048)
			(stroke
				(width 0.1)
				(type default)
			)
			(layer "F.Fab")
		)
		(fp_line
			(start 0.12065 -0.3048)
			(end 0.67945 -0.3048)
			(stroke
				(width 0.1)
				(type default)
			)
			(layer "F.Fab")
		)
		(fp_line
			(start 0.67945 -0.3048)
			(end 0.67945 0.3048)
			(stroke
				(width 0.1)
				(type default)
			)
			(layer "F.Fab")
		)
		(fp_line
			(start -0.67945 -0.305054)
			(end -0.12065 -0.305054)
			(stroke
				(width 0.1)
				(type default)
			)
			(layer "F.Fab")
		)
		(fp_line
			(start -0.12065 -0.305054)
			(end -0.12065 -0.2794)
			(stroke
				(width 0.1)
				(type default)
			)
			(layer "F.Fab")
		)
		(pad "1" smd circle
			(at -0.40005 0 270)
			(size 0 0)
			(layers "F.Cu" "F.Mask" "F.Paste")
			(net "P12V_AUX")
		)
		(pad "2" smd circle
			(at 0.40005 0 270)
			(size 0 0)
			(layers "F.Cu" "F.Mask" "F.Paste")
			(net "P12V_AUX_BLEEDING")
		)
	)
	(footprint ""
		(layer "F.Cu")
		(at 200.995534 -118.782084)
		(property "Reference" "R4157"
			(at 0 0 0)
			(layer "F.SilkS")
			(hide yes)
			(effects
				(font
					(size 1.27 1.27)
				)
			)
		)
		(property "Value" ""
			(at 0 0 0)
			(layer "F.Fab")
			(effects
				(font
					(size 1.27 1.27)
				)
			)
		)
		(duplicate_pad_numbers_are_jumpers no)
		(fp_line
			(start -0.7874 -0.4064)
			(end 0.7874 -0.4064)
			(stroke
				(width 0.1524)
				(type default)
			)
			(layer "F.SilkS")
		)
		(fp_line
			(start -0.7874 0.4064)
			(end -0.7874 -0.4064)
			(stroke
				(width 0.1524)
				(type default)
			)
			(layer "F.SilkS")
		)
		(fp_line
			(start 0.7874 -0.4064)
			(end 0.7874 0.4064)
			(stroke
				(width 0.1524)
				(type default)
			)
			(layer "F.SilkS")
		)
		(fp_line
			(start 0.7874 0.4064)
			(end -0.7874 0.4064)
			(stroke
				(width 0.1524)
				(type default)
			)
			(layer "F.SilkS")
		)
		(fp_line
			(start -0.67945 -0.305054)
			(end -0.12065 -0.305054)
			(stroke
				(width 0.1)
				(type default)
			)
			(layer "F.Fab")
		)
		(fp_line
			(start -0.67945 0.3048)
			(end -0.67945 -0.305054)
			(stroke
				(width 0.1)
				(type default)
			)
			(layer "F.Fab")
		)
		(fp_line
			(start -0.12065 -0.305054)
			(end -0.12065 -0.2794)
			(stroke
				(width 0.1)
				(type default)
			)
			(layer "F.Fab")
		)
		(fp_line
			(start -0.12065 -0.2794)
			(end 0.12065 -0.2794)
			(stroke
				(width 0.1)
				(type default)
			)
			(layer "F.Fab")
		)
		(fp_line
			(start -0.12065 0.2794)
			(end -0.12065 0.3048)
			(stroke
				(width 0.1)
				(type default)
			)
			(layer "F.Fab")
		)
		(fp_line
			(start -0.12065 0.3048)
			(end -0.67945 0.3048)
			(stroke
				(width 0.1)
				(type default)
			)
			(layer "F.Fab")
		)
		(fp_line
			(start 0.120396 0.2794)
			(end -0.12065 0.2794)
			(stroke
				(width 0.1)
				(type default)
			)
			(layer "F.Fab")
		)
		(fp_line
			(start 0.120396 0.3048)
			(end 0.120396 0.2794)
			(stroke
				(width 0.1)
				(type default)
			)
			(layer "F.Fab")
		)
		(fp_line
			(start 0.12065 -0.3048)
			(end 0.67945 -0.3048)
			(stroke
				(width 0.1)
				(type default)
			)
			(layer "F.Fab")
		)
		(fp_line
			(start 0.12065 -0.2794)
			(end 0.12065 -0.3048)
			(stroke
				(width 0.1)
				(type default)
			)
			(layer "F.Fab")
		)
		(fp_line
			(start 0.67945 -0.3048)
			(end 0.67945 0.3048)
			(stroke
				(width 0.1)
				(type default)
			)
			(layer "F.Fab")
		)
		(fp_line
			(start 0.67945 0.3048)
			(end 0.120396 0.3048)
			(stroke
				(width 0.1)
				(type default)
			)
			(layer "F.Fab")
		)
		(pad "1" smd circle
			(at -0.40005 0)
			(size 0 0)
			(layers "F.Cu" "F.Mask" "F.Paste")
			(net "PRSNT_CABLE_GPU_A1_ISO_R_N")
		)
		(pad "2" smd circle
			(at 0.40005 0)
			(size 0 0)
			(layers "F.Cu" "F.Mask" "F.Paste")
			(net "PRSNT_CABLE_GPU_A1_ISO_N")
		)
	)
)
